
INPUT-UNITS     INCHES

WHEEL     1

CIRCLE            71            D10
FLASH     TR57X71X15-45        0.00000  D11
CIRCLE            41            D12
CIRCLE            61            D13
RECTANGLE         12        20   0.00000  D14
RECTANGLE         20        12   0.00000  D15
RECTANGLE         16        24   0.00000  D16
RECTANGLE         24        16   0.00000  D17
CIRCLE            52            D18
FLASH     TR48X62X15-45        0.00000  D19
CIRCLE            48            D20
SQUARE            48   0.00000            D21
SQUARE            52   0.00000            D22
CIRCLE            58            D23
FLASH     TR54X68X15-45        0.00000  D24
CIRCLE            54            D25
SQUARE            54   0.00000            D26
SQUARE            58   0.00000            D27
LINE              62            D28
OBLONG            62       113   0.00000  D29
OBLONG           113        62   0.00000  D30
FLASH     B48-99X62-113X15     0.00000  D31
LINE              52            D32
OBLONG            52       103   0.00000  D33
OBLONG           103        52   0.00000  D34
LINE              56            D35
OBLONG            56       107   0.00000  D36
OBLONG           107        56   0.00000  D37
OBLONG            62        86   0.00000  D38
OBLONG            86        62   0.00000  D39
FLASH     B48-72X62-86X15      0.00000  D40
OBLONG            52        75   0.00000  D41
OBLONG            75        52   0.00000  D42
OBLONG            56        79   0.00000  D43
OBLONG            79        56   0.00000  D44
FLASH     TR44X58X15-45        0.00000  D45
SQUARE            44   0.00000            D46
CIRCLE            44            D47
CIRCLE           149            D48
FLASH     TR135X149X40-45      0.00000  D49
CIRCLE           119            D50
CIRCLE           139            D51
RECTANGLE         18        20   0.00000  D52
RECTANGLE         20        18   0.00000  D53
RECTANGLE         22        24   0.00000  D54
RECTANGLE         24        22   0.00000  D55
RECTANGLE         44        54   0.00000  D56
RECTANGLE         54        44   0.00000  D57
RECTANGLE         48        58   0.00000  D58
RECTANGLE         58        48   0.00000  D59
RECTANGLE         24        52   0.00000  D60
RECTANGLE         52        24   0.00000  D61
RECTANGLE         28        56   0.00000  D62
RECTANGLE         56        28   0.00000  D63
CIRCLE            87            D64
FLASH     TR_C6-ALL            0.00000  D65
CIRCLE          78.5            D66
CIRCLE          43.5            D67
CIRCLE          31.5            D68
CIRCLE          39.5            D69
RECTANGLE         24        56   0.00000  D70
RECTANGLE         56        24   0.00000  D71
RECTANGLE         28        60   0.00000  D72
RECTANGLE         60        28   0.00000  D73
RECTANGLE         28        40   0.00000  D74
RECTANGLE         40        28   0.00000  D75
RECTANGLE         32        44   0.00000  D76
RECTANGLE         44        32   0.00000  D77
RECTANGLE         24        36   0.00000  D78
RECTANGLE         36        24   0.00000  D79
RECTANGLE         24        28   0.00000  D80
RECTANGLE         28        24   0.00000  D81
RECTANGLE         28        32   0.00000  D82
RECTANGLE         32        28   0.00000  D83
RECTANGLE         20        24   0.00000  D84
RECTANGLE         24        20   0.00000  D85
RECTANGLE         24        38   0.00000  D86
RECTANGLE         38        24   0.00000  D87
RECTANGLE         28        42   0.00000  D88
RECTANGLE         42        28   0.00000  D89
RECTANGLE         16        54   0.00000  D90
RECTANGLE         54        16   0.00000  D91
RECTANGLE         20        58   0.00000  D92
RECTANGLE         58        20   0.00000  D93
RECTANGLE         24        54   0.00000  D94
RECTANGLE         54        24   0.00000  D95
RECTANGLE         28        58   0.00000  D96
RECTANGLE         58        28   0.00000  D97
RECTANGLE         24        32   0.00000  D98
RECTANGLE         32        24   0.00000  D99
RECTANGLE         28        36   0.00000  D100
RECTANGLE         36        28   0.00000  D101
RECTANGLE         40        56   0.00000  D102
RECTANGLE         56        40   0.00000  D103
RECTANGLE         44        60   0.00000  D104
RECTANGLE         60        44   0.00000  D105
RECTANGLE         17        24   0.00000  D106
RECTANGLE         24        17   0.00000  D107
RECTANGLE         21        28   0.00000  D108
RECTANGLE         28        21   0.00000  D109
RECTANGLE         14        36   0.00000  D110
RECTANGLE         36        14   0.00000  D111
RECTANGLE         18        40   0.00000  D112
RECTANGLE         40        18   0.00000  D113
FLASH     TR83X97X25-45        0.00000  D114
CIRCLE            85            D115
CIRCLE            46            D116
FLASH     TR42X56X15-45        0.00000  D117
CIRCLE            42            D118
CIRCLE            82            D119
FLASH     TR68X82X15-45        0.00000  D120
CIRCLE            72            D121
RECTANGLE         15        53   0.00000  D122
RECTANGLE         53        15   0.00000  D123
RECTANGLE         19        57   0.00000  D124
RECTANGLE         57        19   0.00000  D125
CIRCLE           155            D126
FLASH     TR141X155X40-45      0.00000  D127
CIRCLE           125            D128
CIRCLE           145            D129
CIRCLE           188            D130
FLASH     TR174X188X40-45      0.00000  D131
CIRCLE           158            D132
CIRCLE           178            D133
FLASH     TR_C20-ALL           0.00000  D134
CIRCLE            30            D135
CIRCLE            34            D136
RECTANGLE         40        50   0.00000  D137
RECTANGLE         50        40   0.00000  D138
RECTANGLE         32        36   0.00000  D139
RECTANGLE         36        32   0.00000  D140
FLASH     TR_C5-ALL            0.00000  D141
CIRCLE            20            D142
CIRCLE            26            D143
CIRCLE            39            D144
CIRCLE           118            D145
LINE               6            D146
LINE               2            D147
LINE             7.4            D148
LINE               4            D149
LINE               8            D150
LINE              10            D151
LINE              25            D152
LINE              18            D153
LINE              15            D154
LINE              40            D155
LINE              20            D156
LINE             5.8            D157
LINE            3.56            D158
LINE              28            D159

